# S9S_MB_2U (Grand Teton) — schematic netlist excerpt (pin names and nets, part order shuffled) for the footprints in the layout excerpt that follows; sources: Cadence DE-HDL packaged netlist, KiCad conversion of 03242023_DA0F0TMBIJ0_F0T_Motherboard_J_brd_V01_OCP.brd

C149  Q_CAP_DIFFBUS  DIFF BUS_0.22UF 6.3V 20% X6S  pkg C0201  page 178 : \1\ = DMI_CPU0_PCH_TX_C_DN<2> ; \2\ = DMI_CPU0_PCH_TX_DN<2>

X21  TP_TDR_4P_FTS  TP_TDR_4P_DIP EMPTY  pkg TH  page 309
  S1  = TDR_DIFF_100_IN2_DN
  P1  = T1_GND
  P2  = T1_GND
  S2  = TDR_DIFF_100_IN2_DP

(kicad_pcb
	(version 20260206)
	(generator "pcbnew")
	(generator_version "10.0")
	(general
		(thickness 1.6)
		(legacy_teardrops no)
	)
	(paper "A4")
	(title_block
		(title "03242023_DA0F0TMBIJ0_F0T_Motherboard_J_brd_V01_OCP.brd")
		(comment 1 "Grand Teton / footprints 2118-2119 of 6105")
	)
	(layers
		(0 "F.Cu" signal "TOP")
		(4 "In1.Cu" signal "GND")
		(6 "In2.Cu" signal "IN1")
		(8 "In3.Cu" signal "GND1")
		(10 "In4.Cu" signal "IN2")
		(12 "In5.Cu" signal "GND2")
		(14 "In6.Cu" signal "IN3")
		(16 "In7.Cu" signal "GND3")
		(18 "In8.Cu" signal "VCC")
		(20 "In9.Cu" signal "VCC1")
		(22 "In10.Cu" signal "GND4")
		(24 "In11.Cu" signal "IN4")
		(26 "In12.Cu" signal "GND5")
		(28 "In13.Cu" signal "IN5")
		(30 "In14.Cu" signal "GND6")
		(32 "In15.Cu" signal "IN6")
		(34 "In16.Cu" signal "GND7")
		(2 "B.Cu" signal "BOTTOM")
		(9 "F.Adhes" user "F.Adhesive")
		(11 "B.Adhes" user "B.Adhesive")
		(13 "F.Paste" user "Package Geometry/Pastemask Top")
		(15 "B.Paste" user "Package Geometry/Pastemask Bottom")
		(5 "F.SilkS" user "Ref Des/Silkscreen Top")
		(7 "B.SilkS" user "Ref Des/Silkscreen Bottom")
		(1 "F.Mask" user "Board Geometry/Soldermask Top")
		(3 "B.Mask" user "Board Geometry/Soldermask Bottom")
		(17 "Dwgs.User" user "User.Drawings")
		(19 "Cmts.User" user "User.Comments")
		(21 "Eco1.User" user "User.Eco1")
		(23 "Eco2.User" user "User.Eco2")
		(25 "Edge.Cuts" user "Board Geometry/Outline")
		(27 "Margin" user)
		(31 "F.CrtYd" user "Package Geometry/Place Bound Top")
		(29 "B.CrtYd" user "Package Geometry/Place Bound Bottom")
		(35 "F.Fab" user "Ref Des/Assembly Top")
		(33 "B.Fab" user "Ref Des/Assembly Bottom")
	)
	(footprint ""
		(layer "F.Cu")
		(at 346.70619 -69.36994 90)
		(property "Reference" "C149"
			(at 0 0 90)
			(layer "F.SilkS")
			(hide yes)
			(effects
				(font
					(size 1.27 1.27)
				)
			)
		)
		(property "Value" ""
			(at 0 0 90)
			(layer "F.Fab")
			(effects
				(font
					(size 1.27 1.27)
				)
			)
		)
		(duplicate_pad_numbers_are_jumpers no)
		(fp_line
			(start 0.299974 -0.150114)
			(end 0.299974 0.150114)
			(stroke
				(width 0.1)
				(type default)
			)
			(layer "F.Fab")
		)
		(fp_line
			(start -0.299974 -0.150114)
			(end 0.299974 -0.150114)
			(stroke
				(width 0.1)
				(type default)
			)
			(layer "F.Fab")
		)
		(fp_line
			(start 0.299974 0.150114)
			(end -0.299974 0.150114)
			(stroke
				(width 0.1)
				(type default)
			)
			(layer "F.Fab")
		)
		(fp_line
			(start -0.299974 0.150114)
			(end -0.299974 -0.150114)
			(stroke
				(width 0.1)
				(type default)
			)
			(layer "F.Fab")
		)
		(pad "1" smd rect
			(at -0.2667 0 90)
			(size 0.3048 0.381)
			(layers "F.Cu" "F.Mask" "F.Paste")
			(net "DMI_CPU0_PCH_TX_C_DN<2>")
		)
		(pad "2" smd rect
			(at 0.2667 0 90)
			(size 0.3048 0.381)
			(layers "F.Cu" "F.Mask" "F.Paste")
			(net "DMI_CPU0_PCH_TX_DN<2>")
		)
		(zone
			(layer "In1.Cu")
			(hatch none 0.5)
			(connect_pads
				(clearance 0)
			)
			(min_thickness 0.25)
			(keepout
				(tracks not_allowed)
				(vias allowed)
				(pads allowed)
				(copperpour not_allowed)
				(footprints allowed)
			)
			(placement
				(enabled no)
				(sheetname "")
			)
			(fill
				(thermal_gap 0.5)
				(thermal_bridge_width 0.5)
				(island_removal_mode 0)
			)
			(polygon
				(pts
					(arc
						(start 346.94749 -69.50964)
						(mid 346.925172 -69.455758)
						(end 346.87129 -69.43344)
					)
					(arc
						(start 346.54109 -69.43344)
						(mid 346.487208 -69.455758)
						(end 346.46489 -69.50964)
					)
					(arc
						(start 346.46489 -69.76364)
						(mid 346.487208 -69.817522)
						(end 346.54109 -69.83984)
					)
					(arc
						(start 346.87129 -69.83984)
						(mid 346.925172 -69.817522)
						(end 346.94749 -69.76364)
					)
				)
			)
		)
		(zone
			(layer "In1.Cu")
			(hatch none 0.5)
			(connect_pads
				(clearance 0)
			)
			(min_thickness 0.25)
			(keepout
				(tracks not_allowed)
				(vias allowed)
				(pads allowed)
				(copperpour not_allowed)
				(footprints allowed)
			)
			(placement
				(enabled no)
				(sheetname "")
			)
			(fill
				(thermal_gap 0.5)
				(thermal_bridge_width 0.5)
				(island_removal_mode 0)
			)
			(polygon
				(pts
					(arc
						(start 346.94749 -68.97624)
						(mid 346.925172 -68.922358)
						(end 346.87129 -68.90004)
					)
					(arc
						(start 346.54109 -68.90004)
						(mid 346.487208 -68.922358)
						(end 346.46489 -68.97624)
					)
					(arc
						(start 346.46489 -69.23024)
						(mid 346.487208 -69.284122)
						(end 346.54109 -69.30644)
					)
					(arc
						(start 346.87129 -69.30644)
						(mid 346.925172 -69.284122)
						(end 346.94749 -69.23024)
					)
				)
			)
		)
	)
	(footprint ""
		(layer "F.Cu")
		(at 501.233948 2.33426 -90)
		(property "Reference" "X21"
			(at -1.33604 3.115818 90)
			(unlocked yes)
			(layer "F.SilkS")
			(effects
				(font
					(size 0.7874 0.5842)
					(thickness 0.1524)
				)
				(justify left)
			)
		)
		(property "Value" ""
			(at 0 0 270)
			(layer "F.Fab")
			(effects
				(font
					(size 1.27 1.27)
				)
			)
		)
		(property "Device Type" "TP_TDR_4P_FTS_MPKT4_H025P0200_I"
			(at 1.30175 1.27 0)
			(unlocked yes)
			(layer "F.Fab")
			(hide yes)
			(effects
				(font
					(size 0.635 0.4064)
					(thickness 0.1524)
				)
			)
		)
		(property "User Part Number" "TP15"
			(at 1.30175 1.27 0)
			(unlocked yes)
			(layer "Cmts.User")
			(hide yes)
			(effects
				(font
					(size 0.635 0.4064)
					(thickness 0.1524)
				)
			)
		)
		(duplicate_pad_numbers_are_jumpers no)
		(fp_line
			(start 0 3.81)
			(end 2.54 3.81)
			(stroke
				(width 0.1524)
				(type default)
			)
			(layer "F.SilkS")
		)
		(fp_line
			(start 2.54 3.81)
			(end 2.54 3.6703)
			(stroke
				(width 0.1524)
				(type default)
			)
			(layer "F.SilkS")
		)
		(fp_line
			(start 0 3.175)
			(end 0 3.81)
			(stroke
				(width 0.1524)
				(type default)
			)
			(layer "F.SilkS")
		)
		(fp_line
			(start 2.54 1.4097)
			(end 2.54 1.1303)
			(stroke
				(width 0.1524)
				(type default)
			)
			(layer "F.SilkS")
		)
		(fp_line
			(start 0 0.635)
			(end 0 1.905)
			(stroke
				(width 0.1524)
				(type default)
			)
			(layer "F.SilkS")
		)
		(fp_line
			(start 2.54 -1.1303)
			(end 2.54 -1.27)
			(stroke
				(width 0.1524)
				(type default)
			)
			(layer "F.SilkS")
		)
		(fp_line
			(start 0 -1.27)
			(end 0 -0.635)
			(stroke
				(width 0.1524)
				(type default)
			)
			(layer "F.SilkS")
		)
		(fp_line
			(start 2.54 -1.27)
			(end 0 -1.27)
			(stroke
				(width 0.1524)
				(type default)
			)
			(layer "F.SilkS")
		)
		(fp_poly
			(pts
				(xy -1.3589 0.041148) (xy -2.8829 0.803148) (xy -2.8829 -0.720852)
			)
			(stroke
				(width 0)
				(type default)
			)
			(fill yes)
			(layer "F.SilkS")
		)
		(fp_line
			(start 0 3.81)
			(end 2.54 3.81)
			(stroke
				(width 0.1)
				(type default)
			)
			(layer "F.Fab")
		)
		(fp_line
			(start 2.54 3.81)
			(end 2.54 -1.27)
			(stroke
				(width 0.1)
				(type default)
			)
			(layer "F.Fab")
		)
		(fp_line
			(start 0 -1.27)
			(end 0 3.81)
			(stroke
				(width 0.1)
				(type default)
			)
			(layer "F.Fab")
		)
		(fp_line
			(start 2.54 -1.27)
			(end 0 -1.27)
			(stroke
				(width 0.1)
				(type default)
			)
			(layer "F.Fab")
		)
		(fp_poly
			(pts
				(xy -0.761746 0) (xy -2.285746 -0.762) (xy -2.285746 0.762)
			)
			(stroke
				(width 0)
				(type default)
			)
			(fill yes)
			(layer "F.Fab")
		)
		(pad "1" thru_hole circle
			(at 0 0 270)
			(size 1.0033 1.0033)
			(drill 0.249936)
			(layers "*.Cu" "*.Mask")
			(remove_unused_layers no)
			(net "TDR_DIFF_100_IN2_DN")
			(clearance 0.10795)
			(thermal_gap 0.10795)
			(padstack
				(mode front_inner_back)
				(layer "Inner"
					(shape circle)
					(size 0.8001 0.8001)
					(clearance 0.1524)
				)
				(layer "B.Cu"
					(shape circle)
					(size 1.0033 1.0033)
					(clearance 0.10795)
				)
			)
		)
		(pad "2" thru_hole circle
			(at 2.54 0 270)
			(size 1.9939 1.9939)
			(drill 0.249936)
			(layers "*.Cu" "*.Mask")
			(remove_unused_layers no)
			(net "T1_GND")
			(clearance 0.10795)
			(thermal_gap 0.10795)
			(padstack
				(mode front_inner_back)
				(layer "Inner"
					(shape circle)
					(size 0.8001 0.8001)
					(clearance 0.1524)
				)
				(layer "B.Cu"
					(shape circle)
					(size 1.9939 1.9939)
					(clearance 0.10795)
				)
			)
		)
		(pad "3" thru_hole circle
			(at 2.54 2.54 270)
			(size 1.9939 1.9939)
			(drill 0.249936)
			(layers "*.Cu" "*.Mask")
			(remove_unused_layers no)
			(net "T1_GND")
			(clearance 0.10795)
			(thermal_gap 0.10795)
			(padstack
				(mode front_inner_back)
				(layer "Inner"
					(shape circle)
					(size 0.8001 0.8001)
					(clearance 0.1524)
				)
				(layer "B.Cu"
					(shape circle)
					(size 1.9939 1.9939)
					(clearance 0.10795)
				)
			)
		)
		(pad "4" thru_hole circle
			(at 0 2.54 270)
			(size 1.0033 1.0033)
			(drill 0.249936)
			(layers "*.Cu" "*.Mask")
			(remove_unused_layers no)
			(net "TDR_DIFF_100_IN2_DP")
			(clearance 0.10795)
			(thermal_gap 0.10795)
			(padstack
				(mode front_inner_back)
				(layer "Inner"
					(shape circle)
					(size 0.8001 0.8001)
					(clearance 0.1524)
				)
				(layer "B.Cu"
					(shape circle)
					(size 1.0033 1.0033)
					(clearance 0.10795)
				)
			)
		)
	)
)
